# SCM (Grand Teton) — schematic netlist excerpt (pin names and nets, part order shuffled) for the footprints in the layout excerpt that follows; sources: Cadence DE-HDL packaged netlist, KiCad conversion of 12092022_DA0F0TMDCD0_F0T_Management_Board_D_brd_V3_OCP.brd

C321  Q_CAP  0.1UF 25V 10% X7R  pkg 0402  page 49 : A = PWR_LED_P5V_AUX ; B = GND

(kicad_pcb
	(version 20260206)
	(generator "pcbnew")
	(generator_version "10.0")
	(general
		(thickness 1.6)
		(legacy_teardrops no)
	)
	(paper "A4")
	(title_block
		(title "12092022_DA0F0TMDCD0_F0T_Management_Board_D_brd_V3_OCP.brd")
		(comment 1 "Grand Teton / footprints 807-807 of 1440")
	)
	(layers
		(0 "F.Cu" signal "TOP")
		(4 "In1.Cu" signal "GND")
		(6 "In2.Cu" signal "IN1")
		(8 "In3.Cu" signal "GND1")
		(10 "In4.Cu" signal "IN2")
		(12 "In5.Cu" signal "VCC")
		(14 "In6.Cu" signal "VCC1")
		(16 "In7.Cu" signal "IN3")
		(18 "In8.Cu" signal "GND2")
		(20 "In9.Cu" signal "IN4")
		(22 "In10.Cu" signal "GND3")
		(2 "B.Cu" signal "BOTTOM")
		(9 "F.Adhes" user "F.Adhesive")
		(11 "B.Adhes" user "B.Adhesive")
		(13 "F.Paste" user "Package Geometry/Pastemask Top")
		(15 "B.Paste" user "Package Geometry/Pastemask Bottom")
		(5 "F.SilkS" user "Ref Des/Silkscreen Top")
		(7 "B.SilkS" user "Ref Des/Silkscreen Bottom")
		(1 "F.Mask" user "Board Geometry/Soldermask Top")
		(3 "B.Mask" user "Board Geometry/Soldermask Bottom")
		(17 "Dwgs.User" user "User.Drawings")
		(19 "Cmts.User" user "User.Comments")
		(21 "Eco1.User" user "User.Eco1")
		(23 "Eco2.User" user "User.Eco2")
		(25 "Edge.Cuts" user "Board Geometry/Outline")
		(27 "Margin" user)
		(31 "F.CrtYd" user "Package Geometry/Place Bound Top")
		(29 "B.CrtYd" user "Package Geometry/Place Bound Bottom")
		(35 "F.Fab" user "Ref Des/Assembly Top")
		(33 "B.Fab" user "Ref Des/Assembly Bottom")
	)
	(footprint ""
		(layer "B.Cu")
		(at 15.113 -18.161 -90)
		(property "Reference" "C321"
			(at 0 0 90)
			(layer "B.SilkS")
			(hide yes)
			(effects
				(font
					(size 1.27 1.27)
				)
				(justify mirror)
			)
		)
		(property "Value" ""
			(at 0 0 90)
			(layer "B.Fab")
			(effects
				(font
					(size 1.27 1.27)
				)
				(justify mirror)
			)
		)
		(duplicate_pad_numbers_are_jumpers no)
		(fp_line
			(start -0.7874 0.4064)
			(end 0.7874 0.4064)
			(stroke
				(width 0.1524)
				(type default)
			)
			(layer "B.SilkS")
		)
		(fp_line
			(start 0.7874 0.4064)
			(end 0.7874 -0.4064)
			(stroke
				(width 0.1524)
				(type default)
			)
			(layer "B.SilkS")
		)
		(fp_line
			(start -0.7874 -0.4064)
			(end -0.7874 0.4064)
			(stroke
				(width 0.1524)
				(type default)
			)
			(layer "B.SilkS")
		)
		(fp_line
			(start 0.7874 -0.4064)
			(end -0.7874 -0.4064)
			(stroke
				(width 0.1524)
				(type default)
			)
			(layer "B.SilkS")
		)
		(fp_line
			(start -0.67945 0.3048)
			(end -0.120396 0.3048)
			(stroke
				(width 0.1)
				(type default)
			)
			(layer "B.Fab")
		)
		(fp_line
			(start -0.120396 0.3048)
			(end -0.120396 0.2794)
			(stroke
				(width 0.1)
				(type default)
			)
			(layer "B.Fab")
		)
		(fp_line
			(start 0.12065 0.3048)
			(end 0.67945 0.3048)
			(stroke
				(width 0.1)
				(type default)
			)
			(layer "B.Fab")
		)
		(fp_line
			(start 0.67945 0.3048)
			(end 0.67945 -0.305054)
			(stroke
				(width 0.1)
				(type default)
			)
			(layer "B.Fab")
		)
		(fp_line
			(start -0.120396 0.2794)
			(end 0.12065 0.2794)
			(stroke
				(width 0.1)
				(type default)
			)
			(layer "B.Fab")
		)
		(fp_line
			(start 0.12065 0.2794)
			(end 0.12065 0.3048)
			(stroke
				(width 0.1)
				(type default)
			)
			(layer "B.Fab")
		)
		(fp_line
			(start -0.12065 -0.2794)
			(end -0.12065 -0.3048)
			(stroke
				(width 0.1)
				(type default)
			)
			(layer "B.Fab")
		)
		(fp_line
			(start 0.12065 -0.2794)
			(end -0.12065 -0.2794)
			(stroke
				(width 0.1)
				(type default)
			)
			(layer "B.Fab")
		)
		(fp_line
			(start -0.67945 -0.3048)
			(end -0.67945 0.3048)
			(stroke
				(width 0.1)
				(type default)
			)
			(layer "B.Fab")
		)
		(fp_line
			(start -0.12065 -0.3048)
			(end -0.67945 -0.3048)
			(stroke
				(width 0.1)
				(type default)
			)
			(layer "B.Fab")
		)
		(fp_line
			(start 0.12065 -0.305054)
			(end 0.12065 -0.2794)
			(stroke
				(width 0.1)
				(type default)
			)
			(layer "B.Fab")
		)
		(fp_line
			(start 0.67945 -0.305054)
			(end 0.12065 -0.305054)
			(stroke
				(width 0.1)
				(type default)
			)
			(layer "B.Fab")
		)
		(pad "1" smd circle
			(at 0.40005 0 90)
			(size 0 0)
			(layers "B.Cu" "B.Mask" "B.Paste")
			(net "PWR_LED_P5V_AUX")
		)
		(pad "2" smd circle
			(at -0.40005 0 90)
			(size 0 0)
			(layers "B.Cu" "B.Mask" "B.Paste")
			(net "GND")
		)
	)
)
